# T6G (Grand Teton) — schematic netlist excerpt (pin names and nets, part order shuffled) for the footprints in the layout excerpt that follows; sources: Cadence DE-HDL packaged netlist, KiCad conversion of 04192023_DAF0TMB3IC0_F0TG_MB_C_brd_V02_OCP.brd

J102  SCONN288_DDR506112002KQ  IO  pkg DDR288S_1-1VXC  page 104
  VIN_BULK0  = P12V_MEM_CPU1
  RFU0  = NC
  VIN_MGMT  = P3V3_AUX
  HSCL  = I3C_SPD_DDRG_CPU1_SCL
  HSDA  = I3C_SPD_DDRG_CPU1_SDA
  VSS0  = GND
  DQ0_A  = M_G_CPU1_SA_DQ<0>
  VSS1  = GND
  DQ1_A  = M_G_CPU1_SA_DQ<1>
  VSS2  = GND
  DQS0_A_T  = M_G_CPU1_SA_DQS_DP<0>
  DQS0_A_C  = M_G_CPU1_SA_DQS_DN<0>
  VSS3  = GND
  DQ4_A  = M_G_CPU1_SA_DQ<4>
  VSS4  = GND
  DQ5_A  = M_G_CPU1_SA_DQ<5>
  VSS5  = GND
  DQ8_A  = M_G_CPU1_SA_DQ<8>
  VSS6  = GND
  DQ9_A  = M_G_CPU1_SA_DQ<9>
  VSS7  = GND
  DQS1_A_T  = M_G_CPU1_SA_DQS_DP<1>
  DQS1_A_C  = M_G_CPU1_SA_DQS_DN<1>
  VSS8  = GND
  DQ12_A  = M_G_CPU1_SA_DQ<12>
  VSS9  = GND
  DQ13_A  = M_G_CPU1_SA_DQ<13>
  VSS10  = GND
  DQ16_A  = M_G_CPU1_SA_DQ<16>
  VSS11  = GND
  DQ17_A  = M_G_CPU1_SA_DQ<17>
  VSS12  = GND
  DQS2_A_T  = M_G_CPU1_SA_DQS_DP<2>
  DQS2_A_C  = M_G_CPU1_SA_DQS_DN<2>
  VSS13  = GND
  DQ20_A  = M_G_CPU1_SA_DQ<20>
  VSS14  = GND
  DQ21_A  = M_G_CPU1_SA_DQ<21>
  VSS15  = GND
  DQ24_A  = M_G_CPU1_SA_DQ<24>
  VSS16  = GND
  DQ25_A  = M_G_CPU1_SA_DQ<25>
  VSS17  = GND
  DQS3_A_T  = M_G_CPU1_SA_DQS_DP<3>
  DQS3_A_C  = M_G_CPU1_SA_DQS_DN<3>
  VSS18  = GND
  DQ28_A  = M_G_CPU1_SA_DQ<28>
  VSS19  = GND
  DQ29_A  = M_G_CPU1_SA_DQ<29>
  VSS20  = GND
  CB0_A  = M_G_CPU1_SA_CB<0>
  VSS21  = GND
  CB1_A  = M_G_CPU1_SA_CB<1>
  VSS22  = GND
  DQS4_A_T  = M_G_CPU1_SA_DQS_DP<4>
  DQS4_A_C  = M_G_CPU1_SA_DQS_DN<4>
  VSS23  = GND
  CB4_A  = M_G_CPU1_SA_CB<4>
  VSS24  = GND
  CB5_A  = M_G_CPU1_SA_CB<5>
  VSS25  = GND
  ALERT_N  = M_G_CPU1_ALERT_N
  VSS26  = GND
  CS0_A_N  = M_G_CPU1_SA_CS_N<0>
  VSS27  = GND
  CA0_A  = M_G_CPU1_SA_CA<0>
  VSS28  = GND
  CA2_A  = M_G_CPU1_SA_CA<2>
  VSS29  = GND
  CA4_A  = M_G_CPU1_SA_CA<4>
  VSS30  = GND
  CA6_A  = M_G_CPU1_SA_CA<6>
  VSS31  = GND
  PAR_A  = M_G_CPU1_SA_PAR
  VSS32  = GND
  CA0_B  = M_G_CPU1_SB_CA<0>
  VSS33  = GND
  CA2_B  = M_G_CPU1_SB_CA<2>
  VSS34  = GND
  CA4_B  = M_G_CPU1_SB_CA<4>
  VSS35  = GND
  CA6_B  = M_G_CPU1_SB_CA<6>
  VSS36  = GND
  CS0_B_N  = M_G_CPU1_SB_CS_N<0>
  VSS37  = GND
  \lbd||rsp_a_n\  = M_G_CPU1_SA_RSP<0>
  \lbs||rsp_b_n\  = M_G_CPU1_SB_RSP<0>
  VSS38  = GND
  CB4_B  = M_G_CPU1_SB_CB<4>
  VSS39  = GND
  CB5_B  = M_G_CPU1_SB_CB<5>
  VSS40  = GND
  \dqs9_b_t||tdqs9_b_t||dbi4_b_n\  = M_G_CPU1_SB_DQS_DP<9>
  \dqs9_b_c||tdqs9_b_c\  = M_G_CPU1_SB_DQS_DN<9>
  VSS41  = GND
  CB0_B  = M_G_CPU1_SB_CB<0>
  VSS42  = GND
  CB1_B  = M_G_CPU1_SB_CB<1>
  VSS43  = GND
  DQ0_B  = M_G_CPU1_SB_DQ<0>
  VSS44  = GND
  DQ1_B  = M_G_CPU1_SB_DQ<1>
  VSS45  = GND
  DQS0_B_T  = M_G_CPU1_SB_DQS_DP<0>
  DQS0_B_C  = M_G_CPU1_SB_DQS_DN<0>
  VSS46  = GND
  DQ4_B  = M_G_CPU1_SB_DQ<4>
  VSS47  = GND
  DQ5_B  = M_G_CPU1_SB_DQ<5>
  VSS48  = GND
  DQ8_B  = M_G_CPU1_SB_DQ<8>
  VSS49  = GND
  DQ9_B  = M_G_CPU1_SB_DQ<9>
  VSS50  = GND
  DQS1_B_T  = M_G_CPU1_SB_DQS_DP<1>
  DQS1_B_C  = M_G_CPU1_SB_DQS_DN<1>
  VSS51  = GND
  DQ12_B  = M_G_CPU1_SB_DQ<12>
  VSS52  = GND
  DQ13_B  = M_G_CPU1_SB_DQ<13>
  VSS53  = GND
  DQ16_B  = M_G_CPU1_SB_DQ<16>
  VSS54  = GND
  DQ17_B  = M_G_CPU1_SB_DQ<17>
  VSS55  = GND
  DQS2_B_T  = M_G_CPU1_SB_DQS_DP<2>
  DQS2_B_C  = M_G_CPU1_SB_DQS_DN<2>
  VSS56  = GND
  DQ20_B  = M_G_CPU1_SB_DQ<20>
  VSS57  = GND
  DQ21_B  = M_G_CPU1_SB_DQ<21>
  VSS58  = GND
  DQ24_B  = M_G_CPU1_SB_DQ<24>
  VSS59  = GND
  DQ25_B  = M_G_CPU1_SB_DQ<25>
  VSS60  = GND
  DQS3_B_T  = M_G_CPU1_SB_DQS_DP<3>
  DQS3_B_C  = M_G_CPU1_SB_DQS_DN<3>
  VSS61  = GND
  DQ28_B  = M_G_CPU1_SB_DQ<28>
  VSS62  = GND
  DQ29_B  = M_G_CPU1_SB_DQ<29>
  VSS63  = GND
  RFU1  = NC
  VIN_BULK1  = P12V_MEM_CPU1
  VIN_BULK2  = P12V_MEM_CPU1
  \pwr_good||fail_n\  = PWRGD_CHG_CPU1_DIMM0
  HAS  = PD_CHG_CPU1_DIMM0_SAA
  RFU2  = NC
  RFU3  = NC
  VSS64  = GND
  DQ2_A  = M_G_CPU1_SA_DQ<2>
  VSS65  = GND
  DQ3_A  = M_G_CPU1_SA_DQ<3>
  VSS66  = GND
  \dqs5_a_c||tdqs5_a_c||dqs5_a_t||tdqs5_a_t\  = M_G_CPU1_SA_DQS_DN<5>
  \dqs5_a_t||tdqs5_a_t\  = M_G_CPU1_SA_DQS_DP<5>
  VSS67  = GND
  DQ6_A  = M_G_CPU1_SA_DQ<6>
  VSS68  = GND
  DQ7_A  = M_G_CPU1_SA_DQ<7>
  VSS69  = GND
  DQ10_A  = M_G_CPU1_SA_DQ<10>
  VSS70  = GND
  DQ11_A  = M_G_CPU1_SA_DQ<11>
  VSS71  = GND
  \dqs6_a_c||tdqs6_a_c||dqs6_a_t||tdqs6_a_t\  = M_G_CPU1_SA_DQS_DN<6>
  \dqs6_a_t||tdqs6_a_t\  = M_G_CPU1_SA_DQS_DP<6>
  VSS72  = GND
  DQ14_A  = M_G_CPU1_SA_DQ<14>
  VSS73  = GND
  DQ15_A  = M_G_CPU1_SA_DQ<15>
  VSS74  = GND
  DQ18_A  = M_G_CPU1_SA_DQ<18>
  VSS75  = GND
  DQ19_A  = M_G_CPU1_SA_DQ<19>
  VSS76  = GND
  \dqs7_a_c||tdqs7_a_c\  = M_G_CPU1_SA_DQS_DN<7>
  \dqs7_a_t||tdqs7_a_t\  = M_G_CPU1_SA_DQS_DP<7>
  VSS77  = GND
  DQ22_A  = M_G_CPU1_SA_DQ<22>
  VSS78  = GND
  DQ23_A  = M_G_CPU1_SA_DQ<23>
  VSS79  = GND
  DQ26_A  = M_G_CPU1_SA_DQ<26>
  VSS80  = GND
  DQ27_A  = M_G_CPU1_SA_DQ<27>
  VSS81  = GND
  \dqs8_a_c||tdqs8_a_c\  = M_G_CPU1_SA_DQS_DN<8>
  \dqs8_a_t||tdqs8_a_t\  = M_G_CPU1_SA_DQS_DP<8>
  VSS82  = GND
  DQ30_A  = M_G_CPU1_SA_DQ<30>
  VSS83  = GND
  DQ31_A  = M_G_CPU1_SA_DQ<31>
  VSS84  = GND
  CB2_A  = M_G_CPU1_SA_CB<2>
  VSS85  = GND
  CB3_A  = M_G_CPU1_SA_CB<3>
  VSS86  = GND
  \dqs9_a_c||tdqs9_a_c\  = M_G_CPU1_SA_DQS_DN<9>
  \dqs9_a_t||tdqs9_a_t\  = M_G_CPU1_SA_DQS_DP<9>
  VSS87  = GND
  CB6_A  = M_G_CPU1_SA_CB<6>
  VSS88  = GND
  CB7_A  = M_G_CPU1_SA_CB<7>
  VSS89  = GND
  RESET_N  = M_G_CPU1_RESET_N
  VSS90  = GND
  CS1_A_N  = M_G_CPU1_SA_CS_N<1>
  VSS91  = GND
  CA1_A  = M_G_CPU1_SA_CA<1>
  VSS92  = GND
  CA3_A  = M_G_CPU1_SA_CA<3>
  VSS93  = GND
  CA5_A  = M_G_CPU1_SA_CA<5>
  VSS94  = GND
  CK_T  = M_G_CPU1_CLK_DP<0>
  CK_C  = M_G_CPU1_CLK_DN<0>
  VSS95  = GND
  RFU4  = NC
  CA1_B  = M_G_CPU1_SB_CA<1>
  VSS96  = GND
  CA3_B  = M_G_CPU1_SB_CA<3>
  VSS97  = GND
  CA5_B  = M_G_CPU1_SB_CA<5>
  VSS98  = GND
  PAR_B  = M_G_CPU1_SB_PAR
  VSS99  = GND
  CS1_B_N  = M_G_CPU1_SB_CS_N<1>
  VSS100  = GND
  RFU5  = NC
  RFU6  = NC
  VSS101  = GND
  CB6_B  = M_G_CPU1_SB_CB<6>
  VSS102  = GND
  CB7_B  = M_G_CPU1_SB_CB<7>
  VSS103  = GND
  DQS4_B_C  = M_G_CPU1_SB_DQS_DN<4>
  DQS4_B_T  = M_G_CPU1_SB_DQS_DP<4>
  VSS104  = GND
  CB2_B  = M_G_CPU1_SB_CB<2>
  VSS105  = GND
  CB3_B  = M_G_CPU1_SB_CB<3>
  VSS106  = GND
  DQ2_B  = M_G_CPU1_SB_DQ<2>
  VSS107  = GND
  DQ3_B  = M_G_CPU1_SB_DQ<3>
  VSS108  = GND
  \dqs5_b_c||tdqs5_b_c\  = M_G_CPU1_SB_DQS_DN<5>
  \dqs5_b_t||tdqs5_b_t\  = M_G_CPU1_SB_DQS_DP<5>
  VSS109  = GND
  DQ6_B  = M_G_CPU1_SB_DQ<6>
  VSS110  = GND
  DQ7_B  = M_G_CPU1_SB_DQ<7>
  VSS111  = GND
  DQ10_B  = M_G_CPU1_SB_DQ<10>
  VSS112  = GND
  DQ11_B  = M_G_CPU1_SB_DQ<11>
  VSS113  = GND
  \dqs6_b_c||tdqs6_b_c\  = M_G_CPU1_SB_DQS_DN<6>
  \dqs6_b_t||tdqs6_b_t\  = M_G_CPU1_SB_DQS_DP<6>
  VSS114  = GND
  DQ14_B  = M_G_CPU1_SB_DQ<14>
  VSS115  = GND
  DQ15_B  = M_G_CPU1_SB_DQ<15>
  VSS116  = GND
  DQ18_B  = M_G_CPU1_SB_DQ<18>
  VSS117  = GND
  DQ19_B  = M_G_CPU1_SB_DQ<19>
  VSS118  = GND
  \dqs7_b_c||tdqs7_b_c\  = M_G_CPU1_SB_DQS_DN<7>
  \dqs7_b_t||tdqs7_b_t\  = M_G_CPU1_SB_DQS_DP<7>
  VSS119  = GND
  DQ22_B  = M_G_CPU1_SB_DQ<22>
  VSS120  = GND
  DQ23_B  = M_G_CPU1_SB_DQ<23>
  VSS121  = GND
  DQ26_B  = M_G_CPU1_SB_DQ<26>
  VSS122  = GND
  DQ27_B  = M_G_CPU1_SB_DQ<27>
  VSS123  = GND
  \dqs8_b_c||tdqs8_b_c\  = M_G_CPU1_SB_DQS_DN<8>
  \dqs8_b_t||tdqs8_b_t\  = M_G_CPU1_SB_DQS_DP<8>
  VSS124  = GND
  DQ30_B  = M_G_CPU1_SB_DQ<30>
  VSS125  = GND
  DQ31_B  = M_G_CPU1_SB_DQ<31>
  VSS126  = GND
  G1  = GND
  G2  = GND
  G3  = GND

(kicad_pcb
	(version 20260206)
	(generator "pcbnew")
	(generator_version "10.0")
	(general
		(thickness 1.6)
		(legacy_teardrops no)
	)
	(paper "A4")
	(title_block
		(title "04192023_DAF0TMB3IC0_F0TG_MB_C_brd_V02_OCP.brd")
		(comment 1 "Grand Teton / footprint 4934 of 8354 (J102), pads 231-276 of 291")
	)
	(layers
		(0 "F.Cu" signal "TOP")
		(4 "In1.Cu" signal "GND")
		(6 "In2.Cu" signal "IN1")
		(8 "In3.Cu" signal "GND1")
		(10 "In4.Cu" signal "IN2")
		(12 "In5.Cu" signal "GND2")
		(14 "In6.Cu" signal "IN3")
		(16 "In7.Cu" signal "GND3")
		(18 "In8.Cu" signal "VCC")
		(20 "In9.Cu" signal "VCC1")
		(22 "In10.Cu" signal "GND4")
		(24 "In11.Cu" signal "IN4")
		(26 "In12.Cu" signal "GND5")
		(28 "In13.Cu" signal "IN5")
		(30 "In14.Cu" signal "GND6")
		(32 "In15.Cu" signal "IN6")
		(34 "In16.Cu" signal "GND7")
		(2 "B.Cu" signal "BOTTOM")
		(9 "F.Adhes" user "F.Adhesive")
		(11 "B.Adhes" user "B.Adhesive")
		(13 "F.Paste" user "Package Geometry/Pastemask Top")
		(15 "B.Paste" user "Package Geometry/Pastemask Bottom")
		(5 "F.SilkS" user "Ref Des/Silkscreen Top")
		(7 "B.SilkS" user "Ref Des/Silkscreen Bottom")
		(1 "F.Mask" user "Board Geometry/Soldermask Top")
		(3 "B.Mask" user "Board Geometry/Soldermask Bottom")
		(17 "Dwgs.User" user "User.Drawings")
		(19 "Cmts.User" user "User.Comments")
		(21 "Eco1.User" user "User.Eco1")
		(23 "Eco2.User" user "User.Eco2")
		(25 "Edge.Cuts" user "Board Geometry/Outline")
		(27 "Margin" user)
		(31 "F.CrtYd" user "Package Geometry/Place Bound Top")
		(29 "B.CrtYd" user "Package Geometry/Place Bound Bottom")
		(35 "F.Fab" user "Ref Des/Assembly Top")
		(33 "B.Fab" user "Ref Des/Assembly Bottom")
	)
	(footprint ""
		(layer "F.Cu")
		(at 166.47795 -255.560322 180)
		(property "Reference" "J102"
			(at -2.7178 -81.857088 0)
			(unlocked yes)
			(layer "F.SilkS")
			(effects
				(font
					(size 0.7874 0.5842)
					(thickness 0.1524)
				)
			)
		)
		(property "Value" ""
			(at 0 0 180)
			(layer "F.Fab")
			(effects
				(font
					(size 1.27 1.27)
				)
			)
		)
		(duplicate_pad_numbers_are_jumpers no)
		(pad "231" smd rect
			(at 2.050034 14.875002 90)
			(size 0.519938 1.4986)
			(layers "F.Cu" "F.Mask" "F.Paste")
			(net "Net_2345")
		)
		(pad "232" smd rect
			(at 2.050034 15.724886 90)
			(size 0.519938 1.4986)
			(layers "F.Cu" "F.Mask" "F.Paste")
			(net "Net_2346")
		)
		(pad "233" smd rect
			(at 2.050034 16.575024 90)
			(size 0.519938 1.4986)
			(layers "F.Cu" "F.Mask" "F.Paste")
			(net "GND")
		)
		(pad "234" smd rect
			(at 2.050034 17.424908 90)
			(size 0.519938 1.4986)
			(layers "F.Cu" "F.Mask" "F.Paste")
			(net "M_G_CPU1_SB_CB<6>")
		)
		(pad "235" smd rect
			(at 2.050034 18.275046 90)
			(size 0.519938 1.4986)
			(layers "F.Cu" "F.Mask" "F.Paste")
			(net "GND")
		)
		(pad "236" smd rect
			(at 2.050034 19.12493 90)
			(size 0.519938 1.4986)
			(layers "F.Cu" "F.Mask" "F.Paste")
			(net "M_G_CPU1_SB_CB<7>")
		)
		(pad "237" smd rect
			(at 2.050034 19.975068 90)
			(size 0.519938 1.4986)
			(layers "F.Cu" "F.Mask" "F.Paste")
			(net "GND")
		)
		(pad "238" smd rect
			(at 2.050034 20.824952 90)
			(size 0.519938 1.4986)
			(layers "F.Cu" "F.Mask" "F.Paste")
			(net "M_G_CPU1_SB_DQS_DN<4>")
		)
		(pad "239" smd rect
			(at 2.050034 21.67509 90)
			(size 0.519938 1.4986)
			(layers "F.Cu" "F.Mask" "F.Paste")
			(net "M_G_CPU1_SB_DQS_DP<4>")
		)
		(pad "240" smd rect
			(at 2.050034 22.524974 90)
			(size 0.519938 1.4986)
			(layers "F.Cu" "F.Mask" "F.Paste")
			(net "GND")
		)
		(pad "241" smd rect
			(at 2.050034 23.375112 90)
			(size 0.519938 1.4986)
			(layers "F.Cu" "F.Mask" "F.Paste")
			(net "M_G_CPU1_SB_CB<2>")
		)
		(pad "242" smd rect
			(at 2.050034 24.224996 90)
			(size 0.519938 1.4986)
			(layers "F.Cu" "F.Mask" "F.Paste")
			(net "GND")
		)
		(pad "243" smd rect
			(at 2.050034 25.07488 90)
			(size 0.519938 1.4986)
			(layers "F.Cu" "F.Mask" "F.Paste")
			(net "M_G_CPU1_SB_CB<3>")
		)
		(pad "244" smd rect
			(at 2.050034 25.925018 90)
			(size 0.519938 1.4986)
			(layers "F.Cu" "F.Mask" "F.Paste")
			(net "GND")
		)
		(pad "245" smd rect
			(at 2.050034 26.774902 90)
			(size 0.519938 1.4986)
			(layers "F.Cu" "F.Mask" "F.Paste")
			(net "M_G_CPU1_SB_DQ<2>")
		)
		(pad "246" smd rect
			(at 2.050034 27.62504 90)
			(size 0.519938 1.4986)
			(layers "F.Cu" "F.Mask" "F.Paste")
			(net "GND")
		)
		(pad "247" smd rect
			(at 2.050034 28.474924 90)
			(size 0.519938 1.4986)
			(layers "F.Cu" "F.Mask" "F.Paste")
			(net "M_G_CPU1_SB_DQ<3>")
		)
		(pad "248" smd rect
			(at 2.050034 29.325062 90)
			(size 0.519938 1.4986)
			(layers "F.Cu" "F.Mask" "F.Paste")
			(net "GND")
		)
		(pad "249" smd rect
			(at 2.050034 30.174946 90)
			(size 0.519938 1.4986)
			(layers "F.Cu" "F.Mask" "F.Paste")
			(net "M_G_CPU1_SB_DQS_DN<5>")
		)
		(pad "250" smd rect
			(at 2.050034 31.025084 90)
			(size 0.519938 1.4986)
			(layers "F.Cu" "F.Mask" "F.Paste")
			(net "M_G_CPU1_SB_DQS_DP<5>")
		)
		(pad "251" smd rect
			(at 2.050034 31.874968 90)
			(size 0.519938 1.4986)
			(layers "F.Cu" "F.Mask" "F.Paste")
			(net "GND")
		)
		(pad "252" smd rect
			(at 2.050034 32.725106 90)
			(size 0.519938 1.4986)
			(layers "F.Cu" "F.Mask" "F.Paste")
			(net "M_G_CPU1_SB_DQ<6>")
		)
		(pad "253" smd rect
			(at 2.050034 33.57499 90)
			(size 0.519938 1.4986)
			(layers "F.Cu" "F.Mask" "F.Paste")
			(net "GND")
		)
		(pad "254" smd rect
			(at 2.050034 34.425128 90)
			(size 0.519938 1.4986)
			(layers "F.Cu" "F.Mask" "F.Paste")
			(net "M_G_CPU1_SB_DQ<7>")
		)
		(pad "255" smd rect
			(at 2.050034 35.275012 90)
			(size 0.519938 1.4986)
			(layers "F.Cu" "F.Mask" "F.Paste")
			(net "GND")
		)
		(pad "256" smd rect
			(at 2.050034 36.124896 90)
			(size 0.519938 1.4986)
			(layers "F.Cu" "F.Mask" "F.Paste")
			(net "M_G_CPU1_SB_DQ<10>")
		)
		(pad "257" smd rect
			(at 2.050034 36.975034 90)
			(size 0.519938 1.4986)
			(layers "F.Cu" "F.Mask" "F.Paste")
			(net "GND")
		)
		(pad "258" smd rect
			(at 2.050034 37.824918 90)
			(size 0.519938 1.4986)
			(layers "F.Cu" "F.Mask" "F.Paste")
			(net "M_G_CPU1_SB_DQ<11>")
		)
		(pad "259" smd rect
			(at 2.050034 38.675056 90)
			(size 0.519938 1.4986)
			(layers "F.Cu" "F.Mask" "F.Paste")
			(net "GND")
		)
		(pad "260" smd rect
			(at 2.050034 39.52494 90)
			(size 0.519938 1.4986)
			(layers "F.Cu" "F.Mask" "F.Paste")
			(net "M_G_CPU1_SB_DQS_DN<6>")
		)
		(pad "261" smd rect
			(at 2.050034 40.375078 90)
			(size 0.519938 1.4986)
			(layers "F.Cu" "F.Mask" "F.Paste")
			(net "M_G_CPU1_SB_DQS_DP<6>")
		)
		(pad "262" smd rect
			(at 2.050034 41.224962 90)
			(size 0.519938 1.4986)
			(layers "F.Cu" "F.Mask" "F.Paste")
			(net "GND")
		)
		(pad "263" smd rect
			(at 2.050034 42.0751 90)
			(size 0.519938 1.4986)
			(layers "F.Cu" "F.Mask" "F.Paste")
			(net "M_G_CPU1_SB_DQ<14>")
		)
		(pad "264" smd rect
			(at 2.050034 42.924984 90)
			(size 0.519938 1.4986)
			(layers "F.Cu" "F.Mask" "F.Paste")
			(net "GND")
		)
		(pad "265" smd rect
			(at 2.050034 43.775122 90)
			(size 0.519938 1.4986)
			(layers "F.Cu" "F.Mask" "F.Paste")
			(net "M_G_CPU1_SB_DQ<15>")
		)
		(pad "266" smd rect
			(at 2.050034 44.625006 90)
			(size 0.519938 1.4986)
			(layers "F.Cu" "F.Mask" "F.Paste")
			(net "GND")
		)
		(pad "267" smd rect
			(at 2.050034 45.47489 90)
			(size 0.519938 1.4986)
			(layers "F.Cu" "F.Mask" "F.Paste")
			(net "M_G_CPU1_SB_DQ<18>")
		)
		(pad "268" smd rect
			(at 2.050034 46.325028 90)
			(size 0.519938 1.4986)
			(layers "F.Cu" "F.Mask" "F.Paste")
			(net "GND")
		)
		(pad "269" smd rect
			(at 2.050034 47.174912 90)
			(size 0.519938 1.4986)
			(layers "F.Cu" "F.Mask" "F.Paste")
			(net "M_G_CPU1_SB_DQ<19>")
		)
		(pad "270" smd rect
			(at 2.050034 48.02505 90)
			(size 0.519938 1.4986)
			(layers "F.Cu" "F.Mask" "F.Paste")
			(net "GND")
		)
		(pad "271" smd rect
			(at 2.050034 48.874934 90)
			(size 0.519938 1.4986)
			(layers "F.Cu" "F.Mask" "F.Paste")
			(net "M_G_CPU1_SB_DQS_DN<7>")
		)
		(pad "272" smd rect
			(at 2.050034 49.725072 90)
			(size 0.519938 1.4986)
			(layers "F.Cu" "F.Mask" "F.Paste")
			(net "M_G_CPU1_SB_DQS_DP<7>")
		)
		(pad "273" smd rect
			(at 2.050034 50.574956 90)
			(size 0.519938 1.4986)
			(layers "F.Cu" "F.Mask" "F.Paste")
			(net "GND")
		)
		(pad "274" smd rect
			(at 2.050034 51.425094 90)
			(size 0.519938 1.4986)
			(layers "F.Cu" "F.Mask" "F.Paste")
			(net "M_G_CPU1_SB_DQ<22>")
		)
		(pad "275" smd rect
			(at 2.050034 52.274978 90)
			(size 0.519938 1.4986)
			(layers "F.Cu" "F.Mask" "F.Paste")
			(net "GND")
		)
		(pad "276" smd rect
			(at 2.050034 53.125116 90)
			(size 0.519938 1.4986)
			(layers "F.Cu" "F.Mask" "F.Paste")
			(net "M_G_CPU1_SB_DQ<23>")
		)
	)
)
